# T6G (Grand Teton) — schematic netlist excerpt (pin names and nets, part order shuffled) for the footprints in the layout excerpt that follows; sources: Cadence DE-HDL packaged netlist, KiCad conversion of 04192023_DAF0TMB3IC0_F0TG_MB_C_brd_V02_OCP.brd

C1751  Q_CAP  0.1UF 25V 10% X7R  pkg 0402  page 240 : A = P3V3_AUX ; B = GND
PR3927  Q_RES  4.99K 0.1% CHIP  pkg 0402LF  page 262 : A = HSC_VSENSE ; B = AGND_HSC

(kicad_pcb
	(version 20260206)
	(generator "pcbnew")
	(generator_version "10.0")
	(general
		(thickness 1.6)
		(legacy_teardrops no)
	)
	(paper "A4")
	(title_block
		(title "04192023_DAF0TMB3IC0_F0TG_MB_C_brd_V02_OCP.brd")
		(comment 1 "Grand Teton / footprints 5227-5228 of 8354")
	)
	(layers
		(0 "F.Cu" signal "TOP")
		(4 "In1.Cu" signal "GND")
		(6 "In2.Cu" signal "IN1")
		(8 "In3.Cu" signal "GND1")
		(10 "In4.Cu" signal "IN2")
		(12 "In5.Cu" signal "GND2")
		(14 "In6.Cu" signal "IN3")
		(16 "In7.Cu" signal "GND3")
		(18 "In8.Cu" signal "VCC")
		(20 "In9.Cu" signal "VCC1")
		(22 "In10.Cu" signal "GND4")
		(24 "In11.Cu" signal "IN4")
		(26 "In12.Cu" signal "GND5")
		(28 "In13.Cu" signal "IN5")
		(30 "In14.Cu" signal "GND6")
		(32 "In15.Cu" signal "IN6")
		(34 "In16.Cu" signal "GND7")
		(2 "B.Cu" signal "BOTTOM")
		(9 "F.Adhes" user "F.Adhesive")
		(11 "B.Adhes" user "B.Adhesive")
		(13 "F.Paste" user "Package Geometry/Pastemask Top")
		(15 "B.Paste" user "Package Geometry/Pastemask Bottom")
		(5 "F.SilkS" user "Ref Des/Silkscreen Top")
		(7 "B.SilkS" user "Ref Des/Silkscreen Bottom")
		(1 "F.Mask" user "Board Geometry/Soldermask Top")
		(3 "B.Mask" user "Board Geometry/Soldermask Bottom")
		(17 "Dwgs.User" user "User.Drawings")
		(19 "Cmts.User" user "User.Comments")
		(21 "Eco1.User" user "User.Eco1")
		(23 "Eco2.User" user "User.Eco2")
		(25 "Edge.Cuts" user "Board Geometry/Outline")
		(27 "Margin" user)
		(31 "F.CrtYd" user "Package Geometry/Place Bound Top")
		(29 "B.CrtYd" user "Package Geometry/Place Bound Bottom")
		(35 "F.Fab" user "Ref Des/Assembly Top")
		(33 "B.Fab" user "Ref Des/Assembly Bottom")
	)
	(footprint ""
		(layer "B.Cu")
		(at 183.36006 -407.222198 -90)
		(property "Reference" "PR3927"
			(at 0 0 90)
			(layer "B.SilkS")
			(hide yes)
			(effects
				(font
					(size 1.27 1.27)
				)
				(justify mirror)
			)
		)
		(property "Value" ""
			(at 0 0 90)
			(layer "B.Fab")
			(effects
				(font
					(size 1.27 1.27)
				)
				(justify mirror)
			)
		)
		(duplicate_pad_numbers_are_jumpers no)
		(fp_line
			(start -0.7874 0.4064)
			(end 0.7874 0.4064)
			(stroke
				(width 0.1524)
				(type default)
			)
			(layer "B.SilkS")
		)
		(fp_line
			(start 0.7874 0.4064)
			(end 0.7874 -0.4064)
			(stroke
				(width 0.1524)
				(type default)
			)
			(layer "B.SilkS")
		)
		(fp_line
			(start -0.7874 -0.4064)
			(end -0.7874 0.4064)
			(stroke
				(width 0.1524)
				(type default)
			)
			(layer "B.SilkS")
		)
		(fp_line
			(start 0.7874 -0.4064)
			(end -0.7874 -0.4064)
			(stroke
				(width 0.1524)
				(type default)
			)
			(layer "B.SilkS")
		)
		(fp_line
			(start -0.67945 0.3048)
			(end -0.120396 0.3048)
			(stroke
				(width 0.1)
				(type default)
			)
			(layer "B.Fab")
		)
		(fp_line
			(start -0.120396 0.3048)
			(end -0.120396 0.2794)
			(stroke
				(width 0.1)
				(type default)
			)
			(layer "B.Fab")
		)
		(fp_line
			(start 0.12065 0.3048)
			(end 0.67945 0.3048)
			(stroke
				(width 0.1)
				(type default)
			)
			(layer "B.Fab")
		)
		(fp_line
			(start 0.67945 0.3048)
			(end 0.67945 -0.305054)
			(stroke
				(width 0.1)
				(type default)
			)
			(layer "B.Fab")
		)
		(fp_line
			(start -0.120396 0.2794)
			(end 0.12065 0.2794)
			(stroke
				(width 0.1)
				(type default)
			)
			(layer "B.Fab")
		)
		(fp_line
			(start 0.12065 0.2794)
			(end 0.12065 0.3048)
			(stroke
				(width 0.1)
				(type default)
			)
			(layer "B.Fab")
		)
		(fp_line
			(start -0.12065 -0.2794)
			(end -0.12065 -0.3048)
			(stroke
				(width 0.1)
				(type default)
			)
			(layer "B.Fab")
		)
		(fp_line
			(start 0.12065 -0.2794)
			(end -0.12065 -0.2794)
			(stroke
				(width 0.1)
				(type default)
			)
			(layer "B.Fab")
		)
		(fp_line
			(start -0.67945 -0.3048)
			(end -0.67945 0.3048)
			(stroke
				(width 0.1)
				(type default)
			)
			(layer "B.Fab")
		)
		(fp_line
			(start -0.12065 -0.3048)
			(end -0.67945 -0.3048)
			(stroke
				(width 0.1)
				(type default)
			)
			(layer "B.Fab")
		)
		(fp_line
			(start 0.12065 -0.305054)
			(end 0.12065 -0.2794)
			(stroke
				(width 0.1)
				(type default)
			)
			(layer "B.Fab")
		)
		(fp_line
			(start 0.67945 -0.305054)
			(end 0.12065 -0.305054)
			(stroke
				(width 0.1)
				(type default)
			)
			(layer "B.Fab")
		)
		(pad "1" smd circle
			(at 0.40005 0 90)
			(size 0 0)
			(layers "B.Cu" "B.Mask" "B.Paste")
			(net "HSC_VSENSE")
		)
		(pad "2" smd circle
			(at -0.40005 0 90)
			(size 0 0)
			(layers "B.Cu" "B.Mask" "B.Paste")
			(net "AGND_HSC")
		)
	)
	(footprint ""
		(layer "B.Cu")
		(at 173.863 -420.243)
		(property "Reference" "C1751"
			(at 0 0 0)
			(layer "B.SilkS")
			(hide yes)
			(effects
				(font
					(size 1.27 1.27)
				)
				(justify mirror)
			)
		)
		(property "Value" ""
			(at 0 0 0)
			(layer "B.Fab")
			(effects
				(font
					(size 1.27 1.27)
				)
				(justify mirror)
			)
		)
		(duplicate_pad_numbers_are_jumpers no)
		(fp_line
			(start -0.7874 -0.4064)
			(end -0.7874 0.4064)
			(stroke
				(width 0.1524)
				(type default)
			)
			(layer "B.SilkS")
		)
		(fp_line
			(start -0.7874 0.4064)
			(end 0.7874 0.4064)
			(stroke
				(width 0.1524)
				(type default)
			)
			(layer "B.SilkS")
		)
		(fp_line
			(start 0.7874 -0.4064)
			(end -0.7874 -0.4064)
			(stroke
				(width 0.1524)
				(type default)
			)
			(layer "B.SilkS")
		)
		(fp_line
			(start 0.7874 0.4064)
			(end 0.7874 -0.4064)
			(stroke
				(width 0.1524)
				(type default)
			)
			(layer "B.SilkS")
		)
		(fp_line
			(start -0.67945 -0.3048)
			(end -0.67945 0.3048)
			(stroke
				(width 0.1)
				(type default)
			)
			(layer "B.Fab")
		)
		(fp_line
			(start -0.67945 0.3048)
			(end -0.120396 0.3048)
			(stroke
				(width 0.1)
				(type default)
			)
			(layer "B.Fab")
		)
		(fp_line
			(start -0.12065 -0.3048)
			(end -0.67945 -0.3048)
			(stroke
				(width 0.1)
				(type default)
			)
			(layer "B.Fab")
		)
		(fp_line
			(start -0.12065 -0.2794)
			(end -0.12065 -0.3048)
			(stroke
				(width 0.1)
				(type default)
			)
			(layer "B.Fab")
		)
		(fp_line
			(start -0.120396 0.2794)
			(end 0.12065 0.2794)
			(stroke
				(width 0.1)
				(type default)
			)
			(layer "B.Fab")
		)
		(fp_line
			(start -0.120396 0.3048)
			(end -0.120396 0.2794)
			(stroke
				(width 0.1)
				(type default)
			)
			(layer "B.Fab")
		)
		(fp_line
			(start 0.12065 -0.305054)
			(end 0.12065 -0.2794)
			(stroke
				(width 0.1)
				(type default)
			)
			(layer "B.Fab")
		)
		(fp_line
			(start 0.12065 -0.2794)
			(end -0.12065 -0.2794)
			(stroke
				(width 0.1)
				(type default)
			)
			(layer "B.Fab")
		)
		(fp_line
			(start 0.12065 0.2794)
			(end 0.12065 0.3048)
			(stroke
				(width 0.1)
				(type default)
			)
			(layer "B.Fab")
		)
		(fp_line
			(start 0.12065 0.3048)
			(end 0.67945 0.3048)
			(stroke
				(width 0.1)
				(type default)
			)
			(layer "B.Fab")
		)
		(fp_line
			(start 0.67945 -0.305054)
			(end 0.12065 -0.305054)
			(stroke
				(width 0.1)
				(type default)
			)
			(layer "B.Fab")
		)
		(fp_line
			(start 0.67945 0.3048)
			(end 0.67945 -0.305054)
			(stroke
				(width 0.1)
				(type default)
			)
			(layer "B.Fab")
		)
		(pad "1" smd circle
			(at 0.40005 0 180)
			(size 0 0)
			(layers "B.Cu" "B.Mask" "B.Paste")
			(net "P3V3_AUX")
		)
		(pad "2" smd circle
			(at -0.40005 0 180)
			(size 0 0)
			(layers "B.Cu" "B.Mask" "B.Paste")
			(net "GND")
		)
	)
)
